(kicad_pcb
	(version 20241229)
	(generator "pcbnew")
	(generator_version "9.0")
	(general
		(thickness 1.61)
		(legacy_teardrops no)
	)
	(paper "A3")
	(title_block
		(title "RDIMM DDR5 Tester")
		(date "2026-05-21")
		(rev "2.2.0")
		(company "Antmicro")
		(comment 9 "footprints 656-660 of 796")
	)
	(layers
		(0 "F.Cu" signal)
		(4 "In1.Cu" power)
		(6 "In2.Cu" mixed)
		(8 "In3.Cu" power)
		(10 "In4.Cu" mixed)
		(12 "In5.Cu" power)
		(14 "In6.Cu" mixed)
		(16 "In7.Cu" power)
		(18 "In8.Cu" power)
		(20 "In9.Cu" mixed)
		(22 "In10.Cu" power)
		(2 "B.Cu" signal)
		(9 "F.Adhes" user "F.Adhesive")
		(11 "B.Adhes" user "B.Adhesive")
		(13 "F.Paste" user)
		(15 "B.Paste" user)
		(5 "F.SilkS" user "F.Silkscreen")
		(7 "B.SilkS" user "B.Silkscreen")
		(1 "F.Mask" user)
		(3 "B.Mask" user)
		(17 "Dwgs.User" user "User.Drawings")
		(19 "Cmts.User" user "User.Comments")
		(21 "Eco1.User" user "User.Eco1")
		(23 "Eco2.User" user "User.Eco2")
		(25 "Edge.Cuts" user)
		(27 "Margin" user)
		(31 "F.CrtYd" user "F.Courtyard")
		(29 "B.CrtYd" user "B.Courtyard")
		(35 "F.Fab" user)
		(33 "B.Fab" user)
	)
	(footprint "antmicro-footprints:C_0402_1005Metric"
		(layer "B.Cu")
		(at 206.18 140.6045 180)
		(descr "Capacitor SMD 0402")
		(tags "capacitor SMD 0402")
		(property "Reference" "C328"
			(at -2.32 0.0045 0)
			(layer "B.SilkS")
			(effects
				(font
					(size 0.7 0.7)
					(thickness 0.15)
				)
				(justify mirror)
			)
		)
		(property "Value" "C_100n_0402"
			(at -1.022927 -2.155213 0)
			(layer "B.Fab")
			(effects
				(font
					(size 0.7 0.7)
					(thickness 0.15)
				)
				(justify left bottom mirror)
			)
		)
		(property "Datasheet" "https://www.murata.com/products/productdetail?partno=GRM155R61H104KE14%23"
			(at 0 0 0)
			(layer "B.Fab")
			(hide yes)
			(effects
				(font
					(size 1.27 1.27)
					(thickness 0.15)
				)
				(justify mirror)
			)
		)
		(property "Manufacturer" "Murata"
			(at 0 0 0)
			(unlocked yes)
			(layer "B.Fab")
			(hide yes)
			(effects
				(font
					(size 1 1)
					(thickness 0.15)
				)
				(justify mirror)
			)
		)
		(property "MPN" "GRM155R61H104KE14D"
			(at 0 0 0)
			(unlocked yes)
			(layer "B.Fab")
			(hide yes)
			(effects
				(font
					(size 1 1)
					(thickness 0.15)
				)
				(justify mirror)
			)
		)
		(property "Val" "100n"
			(at 0 0 0)
			(unlocked yes)
			(layer "B.Fab")
			(hide yes)
			(effects
				(font
					(size 1 1)
					(thickness 0.15)
				)
				(justify mirror)
			)
		)
		(property "License" "Apache-2.0"
			(at 0 0 0)
			(unlocked yes)
			(layer "B.Fab")
			(hide yes)
			(effects
				(font
					(size 1 1)
					(thickness 0.15)
				)
				(justify mirror)
			)
		)
		(property "Author" "Antmicro"
			(at 0 0 0)
			(unlocked yes)
			(layer "B.Fab")
			(hide yes)
			(effects
				(font
					(size 1 1)
					(thickness 0.15)
				)
				(justify mirror)
			)
		)
		(property "Voltage" "50V"
			(at 0 0 0)
			(unlocked yes)
			(layer "B.Fab")
			(hide yes)
			(effects
				(font
					(size 1 1)
					(thickness 0.15)
				)
				(justify mirror)
			)
		)
		(property "Dielectric" "X5R"
			(at 0 0 0)
			(unlocked yes)
			(layer "B.Fab")
			(hide yes)
			(effects
				(font
					(size 1 1)
					(thickness 0.15)
				)
				(justify mirror)
			)
		)
		(sheetname "/Supply/")
		(sheetfile "supply.kicad_sch")
		(attr smd)
		(fp_rect
			(start -0.925 0.47)
			(end 0.925 -0.47)
			(stroke
				(width 0.05)
				(type default)
			)
			(fill no)
			(layer "B.CrtYd")
		)
		(fp_line
			(start 0.504 0.25)
			(end 0.504 -0.248)
			(stroke
				(width 0.15)
				(type solid)
			)
			(layer "B.Fab")
		)
		(fp_line
			(start 0.504 -0.248)
			(end -0.494 -0.248)
			(stroke
				(width 0.15)
				(type solid)
			)
			(layer "B.Fab")
		)
		(fp_line
			(start -0.494 0.25)
			(end 0.504 0.25)
			(stroke
				(width 0.15)
				(type solid)
			)
			(layer "B.Fab")
		)
		(fp_line
			(start -0.494 -0.248)
			(end -0.494 0.25)
			(stroke
				(width 0.15)
				(type solid)
			)
			(layer "B.Fab")
		)
		(fp_text user "${REFERENCE}"
			(at -0.939 -4.599 0)
			(layer "B.Fab")
			(effects
				(font
					(size 0.7 0.7)
					(thickness 0.15)
				)
				(justify left bottom mirror)
			)
		)
		(fp_text user "Author: Antmicro"
			(at -0.939 -3.399 0)
			(layer "B.Fab")
			(effects
				(font
					(size 0.7 0.7)
					(thickness 0.15)
				)
				(justify left bottom mirror)
			)
		)
		(fp_text user "License: Apache-2.0"
			(at -0.939 -5.799 0)
			(layer "B.Fab")
			(effects
				(font
					(size 0.7 0.7)
					(thickness 0.15)
				)
				(justify left bottom mirror)
			)
		)
		(pad "1" smd roundrect
			(at -0.48 0 180)
			(size 0.59 0.64)
			(layers "B.Cu" "B.Mask" "B.Paste")
			(roundrect_rratio 0.25)
			(net 1 "GND")
			(pintype "passive")
		)
		(pad "2" smd roundrect
			(at 0.48 0 180)
			(size 0.59 0.64)
			(layers "B.Cu" "B.Mask" "B.Paste")
			(roundrect_rratio 0.25)
			(net 151 "+3V3")
			(pintype "passive")
		)
	)
	(footprint "antmicro-footprints:R_0402_1005Metric"
		(layer "B.Cu")
		(at 112.33 164.14 -90)
		(descr "Resistor SMD 0402")
		(tags "resistor SMD 0402")
		(property "Reference" "R85"
			(at -1.122484 0.772697 90)
			(layer "B.SilkS")
			(effects
				(font
					(size 0.7 0.7)
					(thickness 0.15)
				)
				(justify left bottom mirror)
			)
		)
		(property "Value" "R_10k_0402"
			(at -1.011843 -1.772047 90)
			(layer "B.Fab")
			(effects
				(font
					(size 0.7 0.7)
					(thickness 0.15)
				)
				(justify left bottom mirror)
			)
		)
		(property "Datasheet" "https://www.bourns.com/docs/product-datasheets/cr.pdf"
			(at 0 0 270)
			(layer "F.Fab")
			(hide yes)
			(effects
				(font
					(size 1.27 1.27)
					(thickness 0.15)
				)
			)
		)
		(property "MPN" "CR0402-FX-1002GLF"
			(at 0 0 270)
			(unlocked yes)
			(layer "B.Fab")
			(hide yes)
			(effects
				(font
					(size 1 1)
					(thickness 0.15)
				)
				(justify mirror)
			)
		)
		(property "Manufacturer" "Bourns"
			(at 0 0 270)
			(unlocked yes)
			(layer "B.Fab")
			(hide yes)
			(effects
				(font
					(size 1 1)
					(thickness 0.15)
				)
				(justify mirror)
			)
		)
		(property "License" "Apache-2.0"
			(at 0 0 270)
			(unlocked yes)
			(layer "B.Fab")
			(hide yes)
			(effects
				(font
					(size 1 1)
					(thickness 0.15)
				)
				(justify mirror)
			)
		)
		(property "Author" "Antmicro"
			(at 0 0 270)
			(unlocked yes)
			(layer "B.Fab")
			(hide yes)
			(effects
				(font
					(size 1 1)
					(thickness 0.15)
				)
				(justify mirror)
			)
		)
		(property "Val" "10k"
			(at 0 0 270)
			(unlocked yes)
			(layer "B.Fab")
			(hide yes)
			(effects
				(font
					(size 1 1)
					(thickness 0.15)
				)
				(justify mirror)
			)
		)
		(property "Tolerance" "1%"
			(at 0 0 270)
			(unlocked yes)
			(layer "B.Fab")
			(hide yes)
			(effects
				(font
					(size 1 1)
					(thickness 0.15)
				)
				(justify mirror)
			)
		)
		(sheetname "/HDMI + SD Card/")
		(sheetfile "hdmi-sd-card.kicad_sch")
		(attr smd)
		(fp_rect
			(start -0.925 0.47)
			(end 0.925 -0.47)
			(stroke
				(width 0.05)
				(type default)
			)
			(fill no)
			(layer "B.CrtYd")
		)
		(fp_rect
			(start -0.5 0.25)
			(end 0.5 -0.25)
			(stroke
				(width 0.15)
				(type solid)
			)
			(fill no)
			(layer "B.Fab")
		)
		(fp_text user "License: Apache-2.0"
			(at -0.95 -5.169 90)
			(layer "B.Fab")
			(effects
				(font
					(size 0.7 0.7)
					(thickness 0.15)
				)
				(justify left bottom mirror)
			)
		)
		(fp_text user "${REFERENCE}"
			(at -0.95 -3.168 90)
			(layer "B.Fab")
			(effects
				(font
					(size 0.7 0.7)
					(thickness 0.15)
				)
				(justify left bottom mirror)
			)
		)
		(fp_text user "Author: Antmicro"
			(at -0.95 -4.169 90)
			(layer "B.Fab")
			(effects
				(font
					(size 0.7 0.7)
					(thickness 0.15)
				)
				(justify left bottom mirror)
			)
		)
		(pad "1" smd roundrect
			(at -0.48 0 270)
			(size 0.59 0.64)
			(layers "B.Cu" "B.Mask" "B.Paste")
			(roundrect_rratio 0.25)
			(net 1 "GND")
			(pintype "passive")
		)
		(pad "2" smd roundrect
			(at 0.48 0 270)
			(size 0.59 0.64)
			(layers "B.Cu" "B.Mask" "B.Paste")
			(roundrect_rratio 0.25)
			(net 297 "/HDMI + SD Card/HDMI_IN_5V")
			(pintype "passive")
		)
	)
	(footprint "antmicro-footprints:C_0402_1005Metric"
		(layer "B.Cu")
		(at 174.48 150.689999 -90)
		(descr "Capacitor SMD 0402")
		(tags "capacitor SMD 0402")
		(property "Reference" "C315"
			(at 1.010001 -0.37 90)
			(layer "B.SilkS")
			(effects
				(font
					(size 0.7 0.7)
					(thickness 0.15)
				)
				(justify left bottom mirror)
			)
		)
		(property "Value" "C_100n_0402"
			(at -1.022927 -2.155213 90)
			(layer "B.Fab")
			(effects
				(font
					(size 0.7 0.7)
					(thickness 0.15)
				)
				(justify left bottom mirror)
			)
		)
		(property "Datasheet" "https://www.murata.com/products/productdetail?partno=GRM155R61H104KE14%23"
			(at 0 0 270)
			(layer "F.Fab")
			(hide yes)
			(effects
				(font
					(size 1.27 1.27)
					(thickness 0.15)
				)
			)
		)
		(property "MPN" "GRM155R61H104KE14D"
			(at 0 0 270)
			(unlocked yes)
			(layer "B.Fab")
			(hide yes)
			(effects
				(font
					(size 1 1)
					(thickness 0.15)
				)
				(justify mirror)
			)
		)
		(property "Manufacturer" "Murata"
			(at 0 0 270)
			(unlocked yes)
			(layer "B.Fab")
			(hide yes)
			(effects
				(font
					(size 1 1)
					(thickness 0.15)
				)
				(justify mirror)
			)
		)
		(property "License" "Apache-2.0"
			(at 0 0 270)
			(unlocked yes)
			(layer "B.Fab")
			(hide yes)
			(effects
				(font
					(size 1 1)
					(thickness 0.15)
				)
				(justify mirror)
			)
		)
		(property "Author" "Antmicro"
			(at 0 0 270)
			(unlocked yes)
			(layer "B.Fab")
			(hide yes)
			(effects
				(font
					(size 1 1)
					(thickness 0.15)
				)
				(justify mirror)
			)
		)
		(property "Val" "100n"
			(at 0 0 270)
			(unlocked yes)
			(layer "B.Fab")
			(hide yes)
			(effects
				(font
					(size 1 1)
					(thickness 0.15)
				)
				(justify mirror)
			)
		)
		(property "Voltage" "50V"
			(at 0 0 270)
			(unlocked yes)
			(layer "B.Fab")
			(hide yes)
			(effects
				(font
					(size 1 1)
					(thickness 0.15)
				)
				(justify mirror)
			)
		)
		(property "Dielectric" "X5R"
			(at 0 0 270)
			(unlocked yes)
			(layer "B.Fab")
			(hide yes)
			(effects
				(font
					(size 1 1)
					(thickness 0.15)
				)
				(justify mirror)
			)
		)
		(sheetname "/FPGA MGT Interface/")
		(sheetfile "fpga-mgt.kicad_sch")
		(attr smd)
		(fp_rect
			(start -0.925 0.47)
			(end 0.925 -0.47)
			(stroke
				(width 0.05)
				(type default)
			)
			(fill no)
			(layer "B.CrtYd")
		)
		(fp_line
			(start -0.494 0.25)
			(end 0.504 0.25)
			(stroke
				(width 0.15)
				(type solid)
			)
			(layer "B.Fab")
		)
		(fp_line
			(start 0.504 0.25)
			(end 0.504 -0.248)
			(stroke
				(width 0.15)
				(type solid)
			)
			(layer "B.Fab")
		)
		(fp_line
			(start -0.494 -0.248)
			(end -0.494 0.25)
			(stroke
				(width 0.15)
				(type solid)
			)
			(layer "B.Fab")
		)
		(fp_line
			(start 0.504 -0.248)
			(end -0.494 -0.248)
			(stroke
				(width 0.15)
				(type solid)
			)
			(layer "B.Fab")
		)
		(fp_text user "Author: Antmicro"
			(at -0.939 -3.399 90)
			(layer "B.Fab")
			(effects
				(font
					(size 0.7 0.7)
					(thickness 0.15)
				)
				(justify left bottom mirror)
			)
		)
		(fp_text user "License: Apache-2.0"
			(at -0.939 -5.799 90)
			(layer "B.Fab")
			(effects
				(font
					(size 0.7 0.7)
					(thickness 0.15)
				)
				(justify left bottom mirror)
			)
		)
		(fp_text user "${REFERENCE}"
			(at -0.939 -4.599 90)
			(layer "B.Fab")
			(effects
				(font
					(size 0.7 0.7)
					(thickness 0.15)
				)
				(justify left bottom mirror)
			)
		)
		(pad "1" smd roundrect
			(at -0.48 0 270)
			(size 0.59 0.64)
			(layers "B.Cu" "B.Mask" "B.Paste")
			(roundrect_rratio 0.25)
			(net 403 "HDMI_REC_CLK_P")
			(pintype "passive")
		)
		(pad "2" smd roundrect
			(at 0.48 0 270)
			(size 0.59 0.64)
			(layers "B.Cu" "B.Mask" "B.Paste")
			(roundrect_rratio 0.25)
			(net 488 "/FPGA MGT Interface/HDMI_REC_CLK_C_P")
			(pintype "passive")
		)
	)
	(footprint "antmicro-footprints:C_0402_1005Metric"
		(layer "B.Cu")
		(at 115.55 159.75 90)
		(descr "Capacitor SMD 0402")
		(tags "capacitor SMD 0402")
		(property "Reference" "C129"
			(at 0.949 0.375501 90)
			(layer "B.SilkS")
			(effects
				(font
					(size 0.7 0.7)
					(thickness 0.15)
				)
				(justify right bottom mirror)
			)
		)
		(property "Value" "C_1u_0402"
			(at -1.022927 -2.155213 90)
			(layer "B.Fab")
			(effects
				(font
					(size 0.7 0.7)
					(thickness 0.15)
				)
				(justify right bottom mirror)
			)
		)
		(property "Datasheet" "https://product.tdk.com/en/search/capacitor/ceramic/mlcc/info?part_no=C1005X6S1A105K050BC"
			(at 0 0 90)
			(layer "F.Fab")
			(hide yes)
			(effects
				(font
					(size 1.27 1.27)
					(thickness 0.15)
				)
			)
		)
		(property "Manufacturer" "TDK"
			(at 0 0 90)
			(unlocked yes)
			(layer "B.Fab")
			(hide yes)
			(effects
				(font
					(size 1 1)
					(thickness 0.15)
				)
				(justify mirror)
			)
		)
		(property "MPN" "C1005X6S1A105K050BC"
			(at 0 0 90)
			(unlocked yes)
			(layer "B.Fab")
			(hide yes)
			(effects
				(font
					(size 1 1)
					(thickness 0.15)
				)
				(justify mirror)
			)
		)
		(property "Val" "1u"
			(at 0 0 90)
			(unlocked yes)
			(layer "B.Fab")
			(hide yes)
			(effects
				(font
					(size 1 1)
					(thickness 0.15)
				)
				(justify mirror)
			)
		)
		(property "License" "Apache-2.0"
			(at 0 0 90)
			(unlocked yes)
			(layer "B.Fab")
			(hide yes)
			(effects
				(font
					(size 1 1)
					(thickness 0.15)
				)
				(justify mirror)
			)
		)
		(property "Author" "Antmicro"
			(at 0 0 90)
			(unlocked yes)
			(layer "B.Fab")
			(hide yes)
			(effects
				(font
					(size 1 1)
					(thickness 0.15)
				)
				(justify mirror)
			)
		)
		(property "Voltage" ""
			(at 0 0 90)
			(unlocked yes)
			(layer "B.Fab")
			(hide yes)
			(effects
				(font
					(size 1 1)
					(thickness 0.15)
				)
				(justify mirror)
			)
		)
		(property "Dielectric" ""
			(at 0 0 90)
			(unlocked yes)
			(layer "B.Fab")
			(hide yes)
			(effects
				(font
					(size 1 1)
					(thickness 0.15)
				)
				(justify mirror)
			)
		)
		(sheetname "/HDMI + SD Card/")
		(sheetfile "hdmi-sd-card.kicad_sch")
		(attr smd)
		(fp_rect
			(start -0.925 0.47)
			(end 0.925 -0.47)
			(stroke
				(width 0.05)
				(type default)
			)
			(fill no)
			(layer "B.CrtYd")
		)
		(fp_line
			(start 0.504 -0.248)
			(end -0.494 -0.248)
			(stroke
				(width 0.15)
				(type solid)
			)
			(layer "B.Fab")
		)
		(fp_line
			(start -0.494 -0.248)
			(end -0.494 0.25)
			(stroke
				(width 0.15)
				(type solid)
			)
			(layer "B.Fab")
		)
		(fp_line
			(start 0.504 0.25)
			(end 0.504 -0.248)
			(stroke
				(width 0.15)
				(type solid)
			)
			(layer "B.Fab")
		)
		(fp_line
			(start -0.494 0.25)
			(end 0.504 0.25)
			(stroke
				(width 0.15)
				(type solid)
			)
			(layer "B.Fab")
		)
		(fp_text user "License: Apache-2.0"
			(at -0.939 -5.799 270)
			(layer "B.Fab")
			(effects
				(font
					(size 0.7 0.7)
					(thickness 0.15)
				)
				(justify left bottom mirror)
			)
		)
		(fp_text user "${REFERENCE}"
			(at -0.939 -4.599 270)
			(layer "B.Fab")
			(effects
				(font
					(size 0.7 0.7)
					(thickness 0.15)
				)
				(justify left bottom mirror)
			)
		)
		(fp_text user "Author: Antmicro"
			(at -0.939 -3.399 270)
			(layer "B.Fab")
			(effects
				(font
					(size 0.7 0.7)
					(thickness 0.15)
				)
				(justify left bottom mirror)
			)
		)
		(pad "1" smd roundrect
			(at -0.48 0 90)
			(size 0.59 0.64)
			(layers "B.Cu" "B.Mask" "B.Paste")
			(roundrect_rratio 0.25)
			(net 151 "+3V3")
			(pintype "passive")
		)
		(pad "2" smd roundrect
			(at 0.48 0 90)
			(size 0.59 0.64)
			(layers "B.Cu" "B.Mask" "B.Paste")
			(roundrect_rratio 0.25)
			(net 1 "GND")
			(pintype "passive")
		)
	)
	(footprint "antmicro-footprints:R_0402_1005Metric"
		(layer "B.Cu")
		(at 254.324499 150.399 180)
		(descr "Resistor SMD 0402")
		(tags "resistor SMD 0402")
		(property "Reference" "R158"
			(at -3.8 -0.3 0)
			(layer "B.SilkS")
			(effects
				(font
					(size 0.7 0.7)
					(thickness 0.15)
				)
				(justify left bottom mirror)
			)
		)
		(property "Value" "R_0R_0402"
			(at -1.011843 -1.772047 0)
			(layer "B.Fab")
			(effects
				(font
					(size 0.7 0.7)
					(thickness 0.15)
				)
				(justify left bottom mirror)
			)
		)
		(property "Datasheet" "https://industrial.panasonic.com/cdbs/www-data/pdf/RDA0000/AOA0000C301.pdf"
			(at 0 0 180)
			(layer "F.Fab")
			(hide yes)
			(effects
				(font
					(size 1.27 1.27)
					(thickness 0.15)
				)
			)
		)
		(property "Manufacturer" "Panasonic"
			(at 0 0 180)
			(unlocked yes)
			(layer "B.Fab")
			(hide yes)
			(effects
				(font
					(size 1 1)
					(thickness 0.15)
				)
				(justify mirror)
			)
		)
		(property "MPN" "ERJ2GE0R00X"
			(at 0 0 180)
			(unlocked yes)
			(layer "B.Fab")
			(hide yes)
			(effects
				(font
					(size 1 1)
					(thickness 0.15)
				)
				(justify mirror)
			)
		)
		(property "Val" "0R"
			(at 0 0 180)
			(unlocked yes)
			(layer "B.Fab")
			(hide yes)
			(effects
				(font
					(size 1 1)
					(thickness 0.15)
				)
				(justify mirror)
			)
		)
		(property "License" "Apache-2.0"
			(at 0 0 180)
			(unlocked yes)
			(layer "B.Fab")
			(hide yes)
			(effects
				(font
					(size 1 1)
					(thickness 0.15)
				)
				(justify mirror)
			)
		)
		(property "Author" "Antmicro"
			(at 0 0 180)
			(unlocked yes)
			(layer "B.Fab")
			(hide yes)
			(effects
				(font
					(size 1 1)
					(thickness 0.15)
				)
				(justify mirror)
			)
		)
		(property "Tolerance" "~"
			(at 0 0 180)
			(unlocked yes)
			(layer "B.Fab")
			(hide yes)
			(effects
				(font
					(size 1 1)
					(thickness 0.15)
				)
				(justify mirror)
			)
		)
		(property "Current" "1A"
			(at 0 0 180)
			(unlocked yes)
			(layer "B.Fab")
			(hide yes)
			(effects
				(font
					(size 1 1)
					(thickness 0.15)
				)
				(justify mirror)
			)
		)
		(sheetname "/Supply/DC-DC IO/")
		(sheetfile "dc-dc-io.kicad_sch")
		(attr smd exclude_from_bom dnp)
		(fp_rect
			(start -0.925 0.47)
			(end 0.925 -0.47)
			(stroke
				(width 0.05)
				(type default)
			)
			(fill no)
			(layer "B.CrtYd")
		)
		(fp_rect
			(start -0.5 0.25)
			(end 0.5 -0.25)
			(stroke
				(width 0.15)
				(type solid)
			)
			(fill no)
			(layer "B.Fab")
		)
		(fp_text user "License: Apache-2.0"
			(at -0.95 -5.169 0)
			(layer "B.Fab")
			(effects
				(font
					(size 0.7 0.7)
					(thickness 0.15)
				)
				(justify left bottom mirror)
			)
		)
		(fp_text user "${REFERENCE}"
			(at -0.95 -3.168 0)
			(layer "B.Fab")
			(effects
				(font
					(size 0.7 0.7)
					(thickness 0.15)
				)
				(justify left bottom mirror)
			)
		)
		(fp_text user "Author: Antmicro"
			(at -0.95 -4.169 0)
			(layer "B.Fab")
			(effects
				(font
					(size 0.7 0.7)
					(thickness 0.15)
				)
				(justify left bottom mirror)
			)
		)
		(pad "1" smd roundrect
			(at -0.48 0 180)
			(size 0.59 0.64)
			(layers "B.Cu" "B.Mask" "B.Paste")
			(roundrect_rratio 0.25)
			(net 1 "GND")
			(pintype "passive")
		)
		(pad "2" smd roundrect
			(at 0.48 0 180)
			(size 0.59 0.64)
			(layers "B.Cu" "B.Mask" "B.Paste")
			(roundrect_rratio 0.25)
			(net 715 "/Supply/DC-DC IO/FB6")
			(pintype "passive")
		)
	)
)
